#ISCELL
  mstr_misc dns *
  *
#ISCELL
  pure_quanta quanta_title_block_c *
  *
#ISCELL
  logical_power universal_power *
  page296_i11
#ISCELL
  logical_power universal_gnd *
  page296_i12
#CELL
  pure_quanta q_cap *
  page296_i13
#CELL
  pure_quanta 74lvc2g07dw7 *
  page296_i16
#ISCELL
  logical_power universal_gnd *
  page296_i17
#ISCELL
  logical_power universal_power *
  page296_i28
#CELL
  pure_quanta q_res *
  page296_i29
#ISCELL
  logical_power universal_gnd *
  page296_i30
#CELL
  pure_quanta q_res *
  page296_i31
#ISCELL
  standard offpage *
  page296_i32
#CELL
  pure_quanta q_res *
  page296_i33
#ISCELL
  logical_power universal_power *
  page296_i34
#CELL
  pure_quanta q_res *
  page296_i35
#ISCELL
  standard offpage *
  page296_i36
#CELL
  pure_quanta q_res *
  page296_i37
#ISCELL
  logical_power universal_gnd *
  page296_i38
#ISCELL
  logical_power universal_power *
  page296_i39
#CELL
  pure_quanta q_res *
  page296_i40
#ISCELL
  standard offpage *
  page296_i41
#CELL
  pure_quanta q_res *
  page296_i42
#ISCELL
  logical_power universal_gnd *
  page296_i43
#ISCELL
  standard offpage *
  page296_i44
#CELL
  pure_quanta q_res *
  page296_i45
#ISCELL
  logical_power universal_power *
  page296_i46
#CELL
  pure_quanta q_res *
  page296_i47
#CELL
  pure_quanta q_res *
  page296_i48
#ISCELL
  logical_power universal_gnd *
  page296_i49
#CELL
  pure_quanta 74lvc2g07dw7 *
  page296_i50
#ISCELL
  standard offpage *
  page296_i51
#CELL
  pure_quanta q_res *
  page296_i53
#ISCELL
  logical_power universal_power *
  page296_i54
#CELL
  pure_quanta q_res *
  page296_i55
#ISCELL
  logical_power universal_power *
  page296_i56
#CELL
  pure_quanta q_res *
  page296_i57
#ISCELL
  standard offpage *
  page296_i58
#CELL
  pure_quanta q_res *
  page296_i62
#ISCELL
  logical_power universal_gnd *
  page296_i63
#ISCELL
  logical_power universal_power *
  page296_i66
#CELL
  pure_quanta q_cap *
  page296_i67
#ISCELL
  logical_power universal_gnd *
  page296_i68
#ISCELL
  logical_power universal_gnd *
  page296_i69
#CELL
  pure_quanta q_res *
  page296_i70
#ISCELL
  logical_power universal_gnd *
  page296_i74
